(kicad_pcb
	(version 20260206)
	(generator "pcbnew")
	(generator_version "10.0")
	(general
		(thickness 1.6)
		(legacy_teardrops no)
	)
	(paper "A4")
	(title_block
		(title "03242023_DA0F0TMBIJ0_F0T_Motherboard_J_brd_V01_OCP.brd")
		(comment 1 "Grand Teton / footprints 1125-1130 of 6105")
	)
	(layers
		(0 "F.Cu" signal "TOP")
		(4 "In1.Cu" signal "GND")
		(6 "In2.Cu" signal "IN1")
		(8 "In3.Cu" signal "GND1")
		(10 "In4.Cu" signal "IN2")
		(12 "In5.Cu" signal "GND2")
		(14 "In6.Cu" signal "IN3")
		(16 "In7.Cu" signal "GND3")
		(18 "In8.Cu" signal "VCC")
		(20 "In9.Cu" signal "VCC1")
		(22 "In10.Cu" signal "GND4")
		(24 "In11.Cu" signal "IN4")
		(26 "In12.Cu" signal "GND5")
		(28 "In13.Cu" signal "IN5")
		(30 "In14.Cu" signal "GND6")
		(32 "In15.Cu" signal "IN6")
		(34 "In16.Cu" signal "GND7")
		(2 "B.Cu" signal "BOTTOM")
		(9 "F.Adhes" user "F.Adhesive")
		(11 "B.Adhes" user "B.Adhesive")
		(13 "F.Paste" user "Package Geometry/Pastemask Top")
		(15 "B.Paste" user "Package Geometry/Pastemask Bottom")
		(5 "F.SilkS" user "Ref Des/Silkscreen Top")
		(7 "B.SilkS" user "Ref Des/Silkscreen Bottom")
		(1 "F.Mask" user "Board Geometry/Soldermask Top")
		(3 "B.Mask" user "Board Geometry/Soldermask Bottom")
		(17 "Dwgs.User" user "User.Drawings")
		(19 "Cmts.User" user "User.Comments")
		(21 "Eco1.User" user "User.Eco1")
		(23 "Eco2.User" user "User.Eco2")
		(25 "Edge.Cuts" user "Board Geometry/Outline")
		(27 "Margin" user)
		(31 "F.CrtYd" user "Package Geometry/Place Bound Top")
		(29 "B.CrtYd" user "Package Geometry/Place Bound Bottom")
		(35 "F.Fab" user "Ref Des/Assembly Top")
		(33 "B.Fab" user "Ref Des/Assembly Bottom")
	)
	(footprint ""
		(layer "F.Cu")
		(at 117.526816 -238.162592 90)
		(property "Reference" "C436"
			(at 0 0 90)
			(layer "F.SilkS")
			(hide yes)
			(effects
				(font
					(size 1.27 1.27)
				)
			)
		)
		(property "Value" ""
			(at 0 0 90)
			(layer "F.Fab")
			(effects
				(font
					(size 1.27 1.27)
				)
			)
		)
		(duplicate_pad_numbers_are_jumpers no)
		(fp_line
			(start 0.7874 -0.4064)
			(end 0.7874 0.4064)
			(stroke
				(width 0.1524)
				(type default)
			)
			(layer "F.SilkS")
		)
		(fp_line
			(start -0.7874 -0.4064)
			(end 0.7874 -0.4064)
			(stroke
				(width 0.1524)
				(type default)
			)
			(layer "F.SilkS")
		)
		(fp_line
			(start 0.7874 0.4064)
			(end -0.7874 0.4064)
			(stroke
				(width 0.1524)
				(type default)
			)
			(layer "F.SilkS")
		)
		(fp_line
			(start -0.7874 0.4064)
			(end -0.7874 -0.4064)
			(stroke
				(width 0.1524)
				(type default)
			)
			(layer "F.SilkS")
		)
		(fp_line
			(start -0.12065 -0.305054)
			(end -0.12065 -0.2794)
			(stroke
				(width 0.1)
				(type default)
			)
			(layer "F.Fab")
		)
		(fp_line
			(start -0.67945 -0.305054)
			(end -0.12065 -0.305054)
			(stroke
				(width 0.1)
				(type default)
			)
			(layer "F.Fab")
		)
		(fp_line
			(start 0.67945 -0.3048)
			(end 0.67945 0.3048)
			(stroke
				(width 0.1)
				(type default)
			)
			(layer "F.Fab")
		)
		(fp_line
			(start 0.12065 -0.3048)
			(end 0.67945 -0.3048)
			(stroke
				(width 0.1)
				(type default)
			)
			(layer "F.Fab")
		)
		(fp_line
			(start 0.12065 -0.2794)
			(end 0.12065 -0.3048)
			(stroke
				(width 0.1)
				(type default)
			)
			(layer "F.Fab")
		)
		(fp_line
			(start -0.12065 -0.2794)
			(end 0.12065 -0.2794)
			(stroke
				(width 0.1)
				(type default)
			)
			(layer "F.Fab")
		)
		(fp_line
			(start 0.120396 0.2794)
			(end -0.12065 0.2794)
			(stroke
				(width 0.1)
				(type default)
			)
			(layer "F.Fab")
		)
		(fp_line
			(start -0.12065 0.2794)
			(end -0.12065 0.3048)
			(stroke
				(width 0.1)
				(type default)
			)
			(layer "F.Fab")
		)
		(fp_line
			(start 0.67945 0.3048)
			(end 0.120396 0.3048)
			(stroke
				(width 0.1)
				(type default)
			)
			(layer "F.Fab")
		)
		(fp_line
			(start 0.120396 0.3048)
			(end 0.120396 0.2794)
			(stroke
				(width 0.1)
				(type default)
			)
			(layer "F.Fab")
		)
		(fp_line
			(start -0.12065 0.3048)
			(end -0.67945 0.3048)
			(stroke
				(width 0.1)
				(type default)
			)
			(layer "F.Fab")
		)
		(fp_line
			(start -0.67945 0.3048)
			(end -0.67945 -0.305054)
			(stroke
				(width 0.1)
				(type default)
			)
			(layer "F.Fab")
		)
		(pad "1" smd circle
			(at -0.40005 0 90)
			(size 0 0)
			(layers "F.Cu" "F.Mask" "F.Paste")
			(net "PVCCINFAON_CPU1")
		)
		(pad "2" smd circle
			(at 0.40005 0 90)
			(size 0 0)
			(layers "F.Cu" "F.Mask" "F.Paste")
			(net "GND")
		)
	)
	(footprint ""
		(layer "F.Cu")
		(at 50.215038 -408.517344 -90)
		(property "Reference" "C709"
			(at 0 0 270)
			(layer "F.SilkS")
			(hide yes)
			(effects
				(font
					(size 1.27 1.27)
				)
			)
		)
		(property "Value" ""
			(at 0 0 270)
			(layer "F.Fab")
			(effects
				(font
					(size 1.27 1.27)
				)
			)
		)
		(duplicate_pad_numbers_are_jumpers no)
		(fp_line
			(start -0.299974 0.150114)
			(end -0.299974 -0.150114)
			(stroke
				(width 0.1)
				(type default)
			)
			(layer "F.Fab")
		)
		(fp_line
			(start 0.299974 0.150114)
			(end -0.299974 0.150114)
			(stroke
				(width 0.1)
				(type default)
			)
			(layer "F.Fab")
		)
		(fp_line
			(start -0.299974 -0.150114)
			(end 0.299974 -0.150114)
			(stroke
				(width 0.1)
				(type default)
			)
			(layer "F.Fab")
		)
		(fp_line
			(start 0.299974 -0.150114)
			(end 0.299974 0.150114)
			(stroke
				(width 0.1)
				(type default)
			)
			(layer "F.Fab")
		)
		(pad "1" smd rect
			(at -0.2667 0 270)
			(size 0.3048 0.381)
			(layers "F.Cu" "F.Mask" "F.Paste")
			(net "P5E_CPU1_PE4_TX_C_DP<0>")
		)
		(pad "2" smd rect
			(at 0.2667 0 270)
			(size 0.3048 0.381)
			(layers "F.Cu" "F.Mask" "F.Paste")
			(net "P5E_CPU1_PE4_TX_DP<0>")
		)
	)
	(footprint ""
		(layer "F.Cu")
		(at 68.093844 -109.483906)
		(property "Reference" "R3731"
			(at 0 0 0)
			(layer "F.SilkS")
			(hide yes)
			(effects
				(font
					(size 1.27 1.27)
				)
			)
		)
		(property "Value" ""
			(at 0 0 0)
			(layer "F.Fab")
			(effects
				(font
					(size 1.27 1.27)
				)
			)
		)
		(duplicate_pad_numbers_are_jumpers no)
		(fp_line
			(start -0.7874 -0.4064)
			(end 0.7874 -0.4064)
			(stroke
				(width 0.1524)
				(type default)
			)
			(layer "F.SilkS")
		)
		(fp_line
			(start -0.7874 0.4064)
			(end -0.7874 -0.4064)
			(stroke
				(width 0.1524)
				(type default)
			)
			(layer "F.SilkS")
		)
		(fp_line
			(start 0.7874 -0.4064)
			(end 0.7874 0.4064)
			(stroke
				(width 0.1524)
				(type default)
			)
			(layer "F.SilkS")
		)
		(fp_line
			(start 0.7874 0.4064)
			(end -0.7874 0.4064)
			(stroke
				(width 0.1524)
				(type default)
			)
			(layer "F.SilkS")
		)
		(fp_line
			(start -0.67945 -0.305054)
			(end -0.12065 -0.305054)
			(stroke
				(width 0.1)
				(type default)
			)
			(layer "F.Fab")
		)
		(fp_line
			(start -0.67945 0.3048)
			(end -0.67945 -0.305054)
			(stroke
				(width 0.1)
				(type default)
			)
			(layer "F.Fab")
		)
		(fp_line
			(start -0.12065 -0.305054)
			(end -0.12065 -0.2794)
			(stroke
				(width 0.1)
				(type default)
			)
			(layer "F.Fab")
		)
		(fp_line
			(start -0.12065 -0.2794)
			(end 0.12065 -0.2794)
			(stroke
				(width 0.1)
				(type default)
			)
			(layer "F.Fab")
		)
		(fp_line
			(start -0.12065 0.2794)
			(end -0.12065 0.3048)
			(stroke
				(width 0.1)
				(type default)
			)
			(layer "F.Fab")
		)
		(fp_line
			(start -0.12065 0.3048)
			(end -0.67945 0.3048)
			(stroke
				(width 0.1)
				(type default)
			)
			(layer "F.Fab")
		)
		(fp_line
			(start 0.120396 0.2794)
			(end -0.12065 0.2794)
			(stroke
				(width 0.1)
				(type default)
			)
			(layer "F.Fab")
		)
		(fp_line
			(start 0.120396 0.3048)
			(end 0.120396 0.2794)
			(stroke
				(width 0.1)
				(type default)
			)
			(layer "F.Fab")
		)
		(fp_line
			(start 0.12065 -0.3048)
			(end 0.67945 -0.3048)
			(stroke
				(width 0.1)
				(type default)
			)
			(layer "F.Fab")
		)
		(fp_line
			(start 0.12065 -0.2794)
			(end 0.12065 -0.3048)
			(stroke
				(width 0.1)
				(type default)
			)
			(layer "F.Fab")
		)
		(fp_line
			(start 0.67945 -0.3048)
			(end 0.67945 0.3048)
			(stroke
				(width 0.1)
				(type default)
			)
			(layer "F.Fab")
		)
		(fp_line
			(start 0.67945 0.3048)
			(end 0.120396 0.3048)
			(stroke
				(width 0.1)
				(type default)
			)
			(layer "F.Fab")
		)
		(pad "1" smd circle
			(at -0.40005 0)
			(size 0 0)
			(layers "F.Cu" "F.Mask" "F.Paste")
			(net "P3V3_AUX")
		)
		(pad "2" smd circle
			(at 0.40005 0)
			(size 0 0)
			(layers "F.Cu" "F.Mask" "F.Paste")
			(net "SMB_LM75_3_3V3AUX_SCL")
		)
	)
	(footprint ""
		(layer "F.Cu")
		(at 193.60388 -102.415848 180)
		(property "Reference" "R269"
			(at 0 0 180)
			(layer "F.SilkS")
			(hide yes)
			(effects
				(font
					(size 1.27 1.27)
				)
			)
		)
		(property "Value" ""
			(at 0 0 180)
			(layer "F.Fab")
			(effects
				(font
					(size 1.27 1.27)
				)
			)
		)
		(duplicate_pad_numbers_are_jumpers no)
		(fp_line
			(start 0.7874 0.4064)
			(end -0.7874 0.4064)
			(stroke
				(width 0.1524)
				(type default)
			)
			(layer "F.SilkS")
		)
		(fp_line
			(start 0.7874 -0.4064)
			(end 0.7874 0.4064)
			(stroke
				(width 0.1524)
				(type default)
			)
			(layer "F.SilkS")
		)
		(fp_line
			(start -0.7874 0.4064)
			(end -0.7874 -0.4064)
			(stroke
				(width 0.1524)
				(type default)
			)
			(layer "F.SilkS")
		)
		(fp_line
			(start -0.7874 -0.4064)
			(end 0.7874 -0.4064)
			(stroke
				(width 0.1524)
				(type default)
			)
			(layer "F.SilkS")
		)
		(fp_line
			(start 0.67945 0.3048)
			(end 0.120396 0.3048)
			(stroke
				(width 0.1)
				(type default)
			)
			(layer "F.Fab")
		)
		(fp_line
			(start 0.67945 -0.3048)
			(end 0.67945 0.3048)
			(stroke
				(width 0.1)
				(type default)
			)
			(layer "F.Fab")
		)
		(fp_line
			(start 0.12065 -0.2794)
			(end 0.12065 -0.3048)
			(stroke
				(width 0.1)
				(type default)
			)
			(layer "F.Fab")
		)
		(fp_line
			(start 0.12065 -0.3048)
			(end 0.67945 -0.3048)
			(stroke
				(width 0.1)
				(type default)
			)
			(layer "F.Fab")
		)
		(fp_line
			(start 0.120396 0.3048)
			(end 0.120396 0.2794)
			(stroke
				(width 0.1)
				(type default)
			)
			(layer "F.Fab")
		)
		(fp_line
			(start 0.120396 0.2794)
			(end -0.12065 0.2794)
			(stroke
				(width 0.1)
				(type default)
			)
			(layer "F.Fab")
		)
		(fp_line
			(start -0.12065 0.3048)
			(end -0.67945 0.3048)
			(stroke
				(width 0.1)
				(type default)
			)
			(layer "F.Fab")
		)
		(fp_line
			(start -0.12065 0.2794)
			(end -0.12065 0.3048)
			(stroke
				(width 0.1)
				(type default)
			)
			(layer "F.Fab")
		)
		(fp_line
			(start -0.12065 -0.2794)
			(end 0.12065 -0.2794)
			(stroke
				(width 0.1)
				(type default)
			)
			(layer "F.Fab")
		)
		(fp_line
			(start -0.12065 -0.305054)
			(end -0.12065 -0.2794)
			(stroke
				(width 0.1)
				(type default)
			)
			(layer "F.Fab")
		)
		(fp_line
			(start -0.67945 0.3048)
			(end -0.67945 -0.305054)
			(stroke
				(width 0.1)
				(type default)
			)
			(layer "F.Fab")
		)
		(fp_line
			(start -0.67945 -0.305054)
			(end -0.12065 -0.305054)
			(stroke
				(width 0.1)
				(type default)
			)
			(layer "F.Fab")
		)
		(pad "1" smd circle
			(at -0.40005 0 180)
			(size 0 0)
			(layers "F.Cu" "F.Mask" "F.Paste")
			(net "FM_ADR_MODE1")
		)
		(pad "2" smd circle
			(at 0.40005 0 180)
			(size 0 0)
			(layers "F.Cu" "F.Mask" "F.Paste")
			(net "FM_ADR_MODE1_R")
		)
	)
	(footprint ""
		(layer "F.Cu")
		(at 122.978926 -122.096784 90)
		(property "Reference" "R4040"
			(at 0 0 90)
			(layer "F.SilkS")
			(hide yes)
			(effects
				(font
					(size 1.27 1.27)
				)
			)
		)
		(property "Value" ""
			(at 0 0 90)
			(layer "F.Fab")
			(effects
				(font
					(size 1.27 1.27)
				)
			)
		)
		(duplicate_pad_numbers_are_jumpers no)
		(fp_line
			(start 0.7874 -0.4064)
			(end 0.7874 0.4064)
			(stroke
				(width 0.1524)
				(type default)
			)
			(layer "F.SilkS")
		)
		(fp_line
			(start -0.7874 -0.4064)
			(end 0.7874 -0.4064)
			(stroke
				(width 0.1524)
				(type default)
			)
			(layer "F.SilkS")
		)
		(fp_line
			(start 0.7874 0.4064)
			(end -0.7874 0.4064)
			(stroke
				(width 0.1524)
				(type default)
			)
			(layer "F.SilkS")
		)
		(fp_line
			(start -0.7874 0.4064)
			(end -0.7874 -0.4064)
			(stroke
				(width 0.1524)
				(type default)
			)
			(layer "F.SilkS")
		)
		(fp_line
			(start -0.12065 -0.305054)
			(end -0.12065 -0.2794)
			(stroke
				(width 0.1)
				(type default)
			)
			(layer "F.Fab")
		)
		(fp_line
			(start -0.67945 -0.305054)
			(end -0.12065 -0.305054)
			(stroke
				(width 0.1)
				(type default)
			)
			(layer "F.Fab")
		)
		(fp_line
			(start 0.67945 -0.3048)
			(end 0.67945 0.3048)
			(stroke
				(width 0.1)
				(type default)
			)
			(layer "F.Fab")
		)
		(fp_line
			(start 0.12065 -0.3048)
			(end 0.67945 -0.3048)
			(stroke
				(width 0.1)
				(type default)
			)
			(layer "F.Fab")
		)
		(fp_line
			(start 0.12065 -0.2794)
			(end 0.12065 -0.3048)
			(stroke
				(width 0.1)
				(type default)
			)
			(layer "F.Fab")
		)
		(fp_line
			(start -0.12065 -0.2794)
			(end 0.12065 -0.2794)
			(stroke
				(width 0.1)
				(type default)
			)
			(layer "F.Fab")
		)
		(fp_line
			(start 0.120396 0.2794)
			(end -0.12065 0.2794)
			(stroke
				(width 0.1)
				(type default)
			)
			(layer "F.Fab")
		)
		(fp_line
			(start -0.12065 0.2794)
			(end -0.12065 0.3048)
			(stroke
				(width 0.1)
				(type default)
			)
			(layer "F.Fab")
		)
		(fp_line
			(start 0.67945 0.3048)
			(end 0.120396 0.3048)
			(stroke
				(width 0.1)
				(type default)
			)
			(layer "F.Fab")
		)
		(fp_line
			(start 0.120396 0.3048)
			(end 0.120396 0.2794)
			(stroke
				(width 0.1)
				(type default)
			)
			(layer "F.Fab")
		)
		(fp_line
			(start -0.12065 0.3048)
			(end -0.67945 0.3048)
			(stroke
				(width 0.1)
				(type default)
			)
			(layer "F.Fab")
		)
		(fp_line
			(start -0.67945 0.3048)
			(end -0.67945 -0.305054)
			(stroke
				(width 0.1)
				(type default)
			)
			(layer "F.Fab")
		)
		(pad "1" smd circle
			(at -0.40005 0 90)
			(size 0 0)
			(layers "F.Cu" "F.Mask" "F.Paste")
			(net "P0V62_CPU1_RST_DDR_VREF")
		)
		(pad "2" smd circle
			(at 0.40005 0 90)
			(size 0 0)
			(layers "F.Cu" "F.Mask" "F.Paste")
			(net "GND")
		)
	)
	(footprint ""
		(layer "F.Cu")
		(at 291.83203 -15.348204)
		(property "Reference" "U271"
			(at -3.98018 -3.442208 0)
			(unlocked yes)
			(layer "F.SilkS")
			(effects
				(font
					(size 0.7874 0.5842)
					(thickness 0.1524)
				)
				(justify left)
			)
		)
		(property "Value" ""
			(at 0 0 0)
			(layer "F.Fab")
			(effects
				(font
					(size 1.27 1.27)
				)
			)
		)
		(duplicate_pad_numbers_are_jumpers no)
		(fp_line
			(start -3.447796 -2.500122)
			(end -3.447796 2.500122)
			(stroke
				(width 0.1524)
				(type default)
			)
			(layer "F.SilkS")
		)
		(fp_line
			(start -3.447796 2.500122)
			(end 3.447796 2.500122)
			(stroke
				(width 0.1524)
				(type default)
			)
			(layer "F.SilkS")
		)
		(fp_line
			(start -1.484122 -2.500122)
			(end -3.447796 -2.500122)
			(stroke
				(width 0.1524)
				(type default)
			)
			(layer "F.SilkS")
		)
		(fp_line
			(start 0 -1.016)
			(end -1.484122 -2.500122)
			(stroke
				(width 0.1524)
				(type default)
			)
			(layer "F.SilkS")
		)
		(fp_line
			(start 1.484122 -2.500122)
			(end 0 -1.016)
			(stroke
				(width 0.1524)
				(type default)
			)
			(layer "F.SilkS")
		)
		(fp_line
			(start 3.447796 -2.500122)
			(end 1.484122 -2.500122)
			(stroke
				(width 0.1524)
				(type default)
			)
			(layer "F.SilkS")
		)
		(fp_line
			(start 3.447796 2.500122)
			(end 3.447796 -2.500122)
			(stroke
				(width 0.1524)
				(type default)
			)
			(layer "F.SilkS")
		)
		(fp_poly
			(pts
				(xy -4.5974 -2.413) (xy -3.5814 -1.905) (xy -4.5974 -1.397)
			)
			(stroke
				(width 0)
				(type default)
			)
			(fill yes)
			(layer "F.SilkS")
		)
		(fp_line
			(start -1.999996 -2.500122)
			(end -1.999996 2.500122)
			(stroke
				(width 0.1)
				(type default)
			)
			(layer "F.Fab")
		)
		(fp_line
			(start -1.999996 2.500122)
			(end 1.999996 2.500122)
			(stroke
				(width 0.1)
				(type default)
			)
			(layer "F.Fab")
		)
		(fp_line
			(start 1.999996 -2.500122)
			(end -1.999996 -2.500122)
			(stroke
				(width 0.1)
				(type default)
			)
			(layer "F.Fab")
		)
		(fp_line
			(start 1.999996 2.500122)
			(end 1.999996 -2.500122)
			(stroke
				(width 0.1)
				(type default)
			)
			(layer "F.Fab")
		)
		(fp_poly
			(pts
				(xy -4.5974 -2.413) (xy -4.5974 -1.397) (xy -3.5814 -1.905)
			)
			(stroke
				(width 0)
				(type default)
			)
			(fill yes)
			(layer "F.Fab")
		)
		(pad "1" smd rect
			(at -2.649982 -1.905 270)
			(size 0.6096 1.3208)
			(layers "F.Cu" "F.Mask" "F.Paste")
			(net "SMB_LM75_1_3V3AUX_SDA_R1")
		)
		(pad "2" smd rect
			(at -2.649982 -0.635 270)
			(size 0.6096 1.3208)
			(layers "F.Cu" "F.Mask" "F.Paste")
			(net "SMB_LM75_1_3V3AUX_SCL_R1")
		)
		(pad "3" smd rect
			(at -2.649982 0.635 270)
			(size 0.6096 1.3208)
			(layers "F.Cu" "F.Mask" "F.Paste")
			(net "FM_G751_1_ALERT_N")
		)
		(pad "4" smd rect
			(at -2.649982 1.905 270)
			(size 0.6096 1.3208)
			(layers "F.Cu" "F.Mask" "F.Paste")
			(net "GND")
		)
		(pad "5" smd rect
			(at 2.649982 1.905 270)
			(size 0.6096 1.3208)
			(layers "F.Cu" "F.Mask" "F.Paste")
			(net "U271_1_ADD2")
		)
		(pad "6" smd rect
			(at 2.649982 0.635 270)
			(size 0.6096 1.3208)
			(layers "F.Cu" "F.Mask" "F.Paste")
			(net "U271_1_ADD1")
		)
		(pad "7" smd rect
			(at 2.649982 -0.635 270)
			(size 0.6096 1.3208)
			(layers "F.Cu" "F.Mask" "F.Paste")
			(net "U271_1_ADD0")
		)
		(pad "8" smd rect
			(at 2.649982 -1.905 270)
			(size 0.6096 1.3208)
			(layers "F.Cu" "F.Mask" "F.Paste")
			(net "P3V3_AUX")
		)
	)
)
